FILE_TYPE = CONNECTIVITY;
{Allegro Design Entry HDL 16.6-p007 (v16-6-112F) 10/10/2012}
"PAGE_NUMBER" = 28;
0"NC";
1"M_F_DQS_DP<17:0>";
2"M_F_ECC<7:0>";
3"M_F_DQ<63:0>";
4"M_F_ODT<3:0>";
5"M_F_CLK_DP<3:0>";
6"M_F_CLK_DN<3:0>";
7"M_F_MA<17:0>";
8"M_F_CS_N<7:0>";
9"M_F_CKE<3:0>";
10"M_F_BG<1:0>";
11"M_F_BA<1:0>";
12"M_F_DQS_DN<17:0>";
13"M_F_DQS_DN<14>";
14"M_F_DQ<50>";
15"M_F_DQ<55>";
16"M_F_DQ<56>";
17"M_F_DQ<57>";
18"M_F_DQS_DP<17>";
19"M_F_DQS_DP<16>";
20"M_F_DQS_DP<15>";
21"M_F_DQS_DP<14>";
22"M_F_DQS_DP<13>";
23"M_F_DQS_DP<12>";
24"M_F_DQS_DP<11>";
25"M_F_DQS_DP<10>";
26"M_F_DQS_DP<9>";
27"M_F_DQS_DP<7>";
28"M_F_DQS_DP<6>";
29"M_F_DQS_DN<17>";
30"M_F_DQS_DN<16>";
31"M_F_DQS_DN<15>";
32"M_F_DQS_DN<13>";
33"M_F_DQS_DN<12>";
34"M_F_DQS_DN<11>";
35"M_F_DQS_DN<10>";
36"M_F_DQS_DN<9>";
37"M_F_DQS_DN<8>";
38"M_F_DQS_DN<7>";
39"M_F_DQS_DN<6>";
40"M_F_DQS_DN<5>";
41"M_F_DQS_DN<4>";
42"M_F_DQS_DN<3>";
43"M_F_DQS_DN<2>";
44"M_F_DQS_DN<1>";
45"M_F_DQS_DN<0>";
46"M_F_DQS_DP<5>";
47"M_F_DQS_DP<4>";
48"M_F_DQS_DP<3>";
49"M_F_DQS_DP<1>";
50"M_F_DQS_DP<0>";
51"M_F_MA<17>";
52"M_F_MA<16>";
53"M_F_MA<15>";
54"M_F_MA<14>";
55"M_F_MA<13>";
56"M_F_MA<12>";
57"M_F_MA<11>";
58"M_F_MA<10>";
59"M_F_MA<9>";
60"M_F_MA<8>";
61"M_F_MA<7>";
62"M_F_MA<6>";
63"M_F_MA<5>";
64"M_F_MA<4>";
65"M_F_MA<3>";
66"M_F_ACT_N";
67"M_F_PAR";
68"M_F_ALERT_N";
69"M_F_BA<1>";
70"M_F_BA<0>";
71"M_F_BG<1>";
72"M_F_BG<0>";
73"M_F_CKE<3>";
74"M_F_CKE<2>";
75"M_F_CKE<1>";
76"M_F_CKE<0>";
77"M_F_CS_N<7>";
78"M_F_CS_N<6>";
79"M_F_CS_N<5>";
80"M_F_CS_N<4>";
81"M_F_CS_N<3>";
82"M_F_CS_N<2>";
83"M_F_CS_N<1>";
84"M_F_CS_N<0>";
85"M_F_MA<2>";
86"M_F_MA<1>";
87"M_F_MA<0>";
88"M_F_ODT<3>";
89"M_F_ODT<1>";
90"M_F_ODT<0>";
91"M_F_DQ<63>";
92"M_F_DQ<62>";
93"M_F_DQ<61>";
94"M_F_DQ<60>";
95"M_F_DQ<59>";
96"M_F_DQ<58>";
97"M_F_DQ<54>";
98"M_F_DQ<53>";
99"M_F_DQ<51>";
100"M_F_DQ<49>";
101"M_F_DQ<48>";
102"M_F_DQ<47>";
103"M_F_DQ<46>";
104"M_F_DQ<45>";
105"M_F_DQ<44>";
106"M_F_DQ<43>";
107"M_F_DQ<42>";
108"M_F_DQ<40>";
109"M_F_DQ<39>";
110"M_F_DQ<38>";
111"M_F_DQ<37>";
112"M_F_DQ<36>";
113"M_F_DQ<35>";
114"M_F_DQ<33>";
115"M_F_DQ<31>";
116"M_F_DQ<30>";
117"M_F_DQ<29>";
118"M_F_DQ<28>";
119"M_F_DQ<27>";
120"M_F_DQ<26>";
121"M_F_DQ<25>";
122"M_F_DQ<24>";
123"M_F_DQ<23>";
124"M_F_DQ<22>";
125"M_F_DQ<21>";
126"M_F_DQ<20>";
127"M_F_DQ<19>";
128"M_F_DQ<18>";
129"M_F_DQ<17>";
130"M_F_DQ<16>";
131"M_F_DQ<15>";
132"M_F_DQ<14>";
133"M_F_DQ<13>";
134"M_F_DQ<12>";
135"M_F_DQ<11>";
136"M_F_CLK_DN<3>";
137"M_F_CLK_DN<2>";
138"M_F_CLK_DN<1>";
139"M_F_CLK_DN<0>";
140"M_F_CLK_DP<3>";
141"M_F_CLK_DP<2>";
142"M_F_CLK_DP<1>";
143"M_F_CLK_DP<0>";
144"M_F_DQ<10>";
145"M_F_DQ<9>";
146"M_F_DQ<8>";
147"M_F_DQ<7>";
148"M_F_DQ<6>";
149"M_F_DQ<4>";
150"M_F_DQ<3>";
151"M_F_DQ<2>";
152"M_F_DQ<1>";
153"M_F_DQ<0>";
154"M_F_ECC<7>";
155"M_F_ECC<6>";
156"M_F_ECC<5>";
157"M_F_ECC<4>";
158"M_F_ECC<3>";
159"M_F_ECC<2>";
160"M_F_ECC<0>";
161"M_F_C<2>";
162"M_F_DQ<5>";
163"M_F_DQ<32>";
164"M_F_DQ<34>";
165"M_F_ODT<2>";
166"M_F_DQ<52>";
167"M_F_DQS_DP<2>";
168"M_F_DQ<41>";
169"M_F_ECC<1>";
170"M_F_DQS_DP<8>";
%"TAP"
"6","(-5575,875)","0","mstr_standard","I10";
;
HDL_TAP"TRUE"
BODY_TYPE"PLUMBING"
CDS_LIB"mstr_standard";
"B \NAC \NWC"5;
"S \NAC"
BN"1"142;
%"TAP"
"6","(-2850,1425)","2","mstr_standard","I100";
;
HDL_TAP"TRUE"
BODY_TYPE"PLUMBING"
CDS_LIB"mstr_standard";
"B \NAC \NWC"4;
"S \NAC"
BN"0"90;
%"TAP"
"6","(-2850,1575)","2","mstr_standard","I101";
;
HDL_TAP"TRUE"
BODY_TYPE"PLUMBING"
CDS_LIB"mstr_standard";
"B \NAC \NWC"4;
"S \NAC"
BN"3"88;
%"TAP"
"6","(-2850,1525)","2","mstr_standard","I102";
;
HDL_TAP"TRUE"
BODY_TYPE"PLUMBING"
CDS_LIB"mstr_standard";
"B \NAC \NWC"4;
"S \NAC"
BN"2"165;
%"TAP"
"6","(-2850,1675)","2","mstr_standard","I103";
;
HDL_TAP"TRUE"
BODY_TYPE"PLUMBING"
CDS_LIB"mstr_standard";
"B \NAC \NWC"9;
"S \NAC"
BN"0"76;
%"TAP"
"6","(-2850,1725)","2","mstr_standard","I104";
;
HDL_TAP"TRUE"
BODY_TYPE"PLUMBING"
CDS_LIB"mstr_standard";
"B \NAC \NWC"9;
"S \NAC"
BN"1"75;
%"TAP"
"6","(-2850,1825)","2","mstr_standard","I105";
;
HDL_TAP"TRUE"
BODY_TYPE"PLUMBING"
CDS_LIB"mstr_standard";
"B \NAC \NWC"9;
"S \NAC"
BN"3"73;
%"TAP"
"6","(-2850,1775)","2","mstr_standard","I106";
;
HDL_TAP"TRUE"
BODY_TYPE"PLUMBING"
CDS_LIB"mstr_standard";
"B \NAC \NWC"9;
"S \NAC"
BN"2"74;
%"TAP"
"6","(-2850,1925)","2","mstr_standard","I107";
;
HDL_TAP"TRUE"
BODY_TYPE"PLUMBING"
CDS_LIB"mstr_standard";
"B \NAC \NWC"7;
"S \NAC"
BN"0"87;
%"TAP"
"6","(-2850,1975)","2","mstr_standard","I108";
;
HDL_TAP"TRUE"
BODY_TYPE"PLUMBING"
CDS_LIB"mstr_standard";
"B \NAC \NWC"7;
"S \NAC"
BN"1"86;
%"TAP"
"6","(-2850,2075)","2","mstr_standard","I109";
;
HDL_TAP"TRUE"
BODY_TYPE"PLUMBING"
CDS_LIB"mstr_standard";
"B \NAC \NWC"7;
"S \NAC"
BN"3"65;
%"TAP"
"6","(-5575,925)","0","mstr_standard","I11";
;
HDL_TAP"TRUE"
BODY_TYPE"PLUMBING"
CDS_LIB"mstr_standard";
"B \NAC \NWC"5;
"S \NAC"
BN"2"141;
%"TAP"
"6","(-2850,2025)","2","mstr_standard","I110";
;
HDL_TAP"TRUE"
BODY_TYPE"PLUMBING"
CDS_LIB"mstr_standard";
"B \NAC \NWC"7;
"S \NAC"
BN"2"85;
%"TAP"
"6","(-2850,2125)","2","mstr_standard","I111";
;
HDL_TAP"TRUE"
BODY_TYPE"PLUMBING"
CDS_LIB"mstr_standard";
"B \NAC \NWC"7;
"S \NAC"
BN"4"64;
%"TAP"
"6","(-2850,2175)","2","mstr_standard","I112";
;
HDL_TAP"TRUE"
BODY_TYPE"PLUMBING"
CDS_LIB"mstr_standard";
"B \NAC \NWC"7;
"S \NAC"
BN"5"63;
%"TAP"
"6","(-2850,2225)","2","mstr_standard","I113";
;
HDL_TAP"TRUE"
BODY_TYPE"PLUMBING"
CDS_LIB"mstr_standard";
"B \NAC \NWC"7;
"S \NAC"
BN"6"62;
%"TAP"
"6","(-2850,2375)","2","mstr_standard","I114";
;
HDL_TAP"TRUE"
BODY_TYPE"PLUMBING"
CDS_LIB"mstr_standard";
"B \NAC \NWC"7;
"S \NAC"
BN"9"59;
%"TAP"
"6","(-2850,2325)","2","mstr_standard","I115";
;
HDL_TAP"TRUE"
BODY_TYPE"PLUMBING"
CDS_LIB"mstr_standard";
"B \NAC \NWC"7;
"S \NAC"
BN"8"60;
%"TAP"
"6","(-2850,2275)","2","mstr_standard","I116";
;
HDL_TAP"TRUE"
BODY_TYPE"PLUMBING"
CDS_LIB"mstr_standard";
"B \NAC \NWC"7;
"S \NAC"
BN"7"61;
%"TAP"
"6","(-2850,2475)","2","mstr_standard","I117";
;
HDL_TAP"TRUE"
BODY_TYPE"PLUMBING"
CDS_LIB"mstr_standard";
"B \NAC \NWC"7;
"S \NAC"
BN"11"57;
%"TAP"
"6","(-2850,2425)","2","mstr_standard","I118";
;
HDL_TAP"TRUE"
BODY_TYPE"PLUMBING"
CDS_LIB"mstr_standard";
"B \NAC \NWC"7;
"S \NAC"
BN"10"58;
%"TAP"
"6","(-2850,2525)","2","mstr_standard","I119";
;
HDL_TAP"TRUE"
BODY_TYPE"PLUMBING"
CDS_LIB"mstr_standard";
"B \NAC \NWC"7;
"S \NAC"
BN"12"56;
%"TAP"
"6","(-5575,975)","0","mstr_standard","I12";
;
HDL_TAP"TRUE"
BODY_TYPE"PLUMBING"
CDS_LIB"mstr_standard";
"B \NAC \NWC"5;
"S \NAC"
BN"3"140;
%"TAP"
"6","(-2850,2575)","2","mstr_standard","I120";
;
HDL_TAP"TRUE"
BODY_TYPE"PLUMBING"
CDS_LIB"mstr_standard";
"B \NAC \NWC"7;
"S \NAC"
BN"13"55;
%"TAP"
"6","(-2850,2625)","2","mstr_standard","I121";
;
HDL_TAP"TRUE"
BODY_TYPE"PLUMBING"
CDS_LIB"mstr_standard";
"B \NAC \NWC"7;
"S \NAC"
BN"14"54;
%"TAP"
"6","(-2850,2725)","2","mstr_standard","I122";
;
HDL_TAP"TRUE"
BODY_TYPE"PLUMBING"
CDS_LIB"mstr_standard";
"B \NAC \NWC"7;
"S \NAC"
BN"16"52;
%"TAP"
"6","(-2850,2675)","2","mstr_standard","I123";
;
HDL_TAP"TRUE"
BODY_TYPE"PLUMBING"
CDS_LIB"mstr_standard";
"B \NAC \NWC"7;
"S \NAC"
BN"15"53;
%"TAP"
"6","(-2850,2775)","2","mstr_standard","I124";
;
HDL_TAP"TRUE"
BODY_TYPE"PLUMBING"
CDS_LIB"mstr_standard";
"B \NAC \NWC"7;
"S \NAC"
BN"17"51;
%"TAP"
"6","(-2850,2875)","2","mstr_standard","I125";
;
HDL_TAP"TRUE"
BODY_TYPE"PLUMBING"
CDS_LIB"mstr_standard";
"B \NAC \NWC"12;
"S \NAC"
BN"0"45;
%"TAP"
"6","(-2850,2975)","2","mstr_standard","I126";
;
HDL_TAP"TRUE"
BODY_TYPE"PLUMBING"
CDS_LIB"mstr_standard";
"B \NAC \NWC"12;
"S \NAC"
BN"2"43;
%"TAP"
"6","(-2850,2925)","2","mstr_standard","I127";
;
HDL_TAP"TRUE"
BODY_TYPE"PLUMBING"
CDS_LIB"mstr_standard";
"B \NAC \NWC"12;
"S \NAC"
BN"1"44;
%"TAP"
"6","(-2850,3025)","2","mstr_standard","I128";
;
HDL_TAP"TRUE"
BODY_TYPE"PLUMBING"
CDS_LIB"mstr_standard";
"B \NAC \NWC"12;
"S \NAC"
BN"3"42;
%"TAP"
"6","(-2850,3075)","2","mstr_standard","I129";
;
HDL_TAP"TRUE"
BODY_TYPE"PLUMBING"
CDS_LIB"mstr_standard";
"B \NAC \NWC"12;
"S \NAC"
BN"4"41;
%"TAP"
"6","(-5575,1075)","0","mstr_standard","I13";
;
HDL_TAP"TRUE"
BODY_TYPE"PLUMBING"
CDS_LIB"mstr_standard";
"B \NAC \NWC"2;
"S \NAC"
BN"0"160;
%"TAP"
"6","(-2850,3125)","2","mstr_standard","I130";
;
HDL_TAP"TRUE"
BODY_TYPE"PLUMBING"
CDS_LIB"mstr_standard";
"B \NAC \NWC"12;
"S \NAC"
BN"5"40;
%"TAP"
"6","(-2850,3225)","2","mstr_standard","I131";
;
HDL_TAP"TRUE"
BODY_TYPE"PLUMBING"
CDS_LIB"mstr_standard";
"B \NAC \NWC"12;
"S \NAC"
BN"7"38;
%"TAP"
"6","(-2850,3175)","2","mstr_standard","I132";
;
HDL_TAP"TRUE"
BODY_TYPE"PLUMBING"
CDS_LIB"mstr_standard";
"B \NAC \NWC"12;
"S \NAC"
BN"6"39;
%"TAP"
"6","(-2850,3275)","2","mstr_standard","I133";
;
HDL_TAP"TRUE"
BODY_TYPE"PLUMBING"
CDS_LIB"mstr_standard";
"B \NAC \NWC"12;
"S \NAC"
BN"8"37;
%"TAP"
"6","(-2850,3375)","2","mstr_standard","I134";
;
HDL_TAP"TRUE"
BODY_TYPE"PLUMBING"
CDS_LIB"mstr_standard";
"B \NAC \NWC"12;
"S \NAC"
BN"10"35;
%"TAP"
"6","(-2850,3325)","2","mstr_standard","I135";
;
HDL_TAP"TRUE"
BODY_TYPE"PLUMBING"
CDS_LIB"mstr_standard";
"B \NAC \NWC"12;
"S \NAC"
BN"9"36;
%"TAP"
"6","(-2850,3525)","2","mstr_standard","I136";
;
HDL_TAP"TRUE"
BODY_TYPE"PLUMBING"
CDS_LIB"mstr_standard";
"B \NAC \NWC"12;
"S \NAC"
BN"13"32;
%"TAP"
"6","(-2850,3425)","2","mstr_standard","I137";
;
HDL_TAP"TRUE"
BODY_TYPE"PLUMBING"
CDS_LIB"mstr_standard";
"B \NAC \NWC"12;
"S \NAC"
BN"11"34;
%"TAP"
"6","(-2850,3475)","2","mstr_standard","I138";
;
HDL_TAP"TRUE"
BODY_TYPE"PLUMBING"
CDS_LIB"mstr_standard";
"B \NAC \NWC"12;
"S \NAC"
BN"12"33;
%"TAP"
"6","(-2850,3625)","2","mstr_standard","I139";
;
HDL_TAP"TRUE"
BODY_TYPE"PLUMBING"
CDS_LIB"mstr_standard";
"B \NAC \NWC"12;
"S \NAC"
BN"15"31;
%"TAP"
"6","(-5575,1125)","0","mstr_standard","I14";
;
HDL_TAP"TRUE"
BODY_TYPE"PLUMBING"
CDS_LIB"mstr_standard";
"B \NAC \NWC"2;
"S \NAC"
BN"1"169;
%"TAP"
"6","(-2850,3575)","2","mstr_standard","I140";
;
HDL_TAP"TRUE"
BODY_TYPE"PLUMBING"
CDS_LIB"mstr_standard";
"B \NAC \NWC"12;
"S \NAC"
BN"14"13;
%"TAP"
"6","(-2850,3725)","2","mstr_standard","I141";
;
HDL_TAP"TRUE"
BODY_TYPE"PLUMBING"
CDS_LIB"mstr_standard";
"B \NAC \NWC"12;
"S \NAC"
BN"17"29;
%"TAP"
"6","(-2850,3675)","2","mstr_standard","I142";
;
HDL_TAP"TRUE"
BODY_TYPE"PLUMBING"
CDS_LIB"mstr_standard";
"B \NAC \NWC"12;
"S \NAC"
BN"16"30;
%"TAP"
"6","(-2850,3875)","2","mstr_standard","I143";
;
HDL_TAP"TRUE"
BODY_TYPE"PLUMBING"
CDS_LIB"mstr_standard";
"B \NAC \NWC"1;
"S \NAC"
BN"1"49;
%"TAP"
"6","(-2850,3825)","2","mstr_standard","I144";
;
HDL_TAP"TRUE"
BODY_TYPE"PLUMBING"
CDS_LIB"mstr_standard";
"B \NAC \NWC"1;
"S \NAC"
BN"0"50;
%"TAP"
"6","(-2850,4025)","2","mstr_standard","I145";
;
HDL_TAP"TRUE"
BODY_TYPE"PLUMBING"
CDS_LIB"mstr_standard";
"B \NAC \NWC"1;
"S \NAC"
BN"4"47;
%"TAP"
"6","(-2850,3975)","2","mstr_standard","I146";
;
HDL_TAP"TRUE"
BODY_TYPE"PLUMBING"
CDS_LIB"mstr_standard";
"B \NAC \NWC"1;
"S \NAC"
BN"3"48;
%"TAP"
"6","(-2850,3925)","2","mstr_standard","I147";
;
HDL_TAP"TRUE"
BODY_TYPE"PLUMBING"
CDS_LIB"mstr_standard";
"B \NAC \NWC"1;
"S \NAC"
BN"2"167;
%"TAP"
"6","(-5575,1175)","0","mstr_standard","I15";
;
HDL_TAP"TRUE"
BODY_TYPE"PLUMBING"
CDS_LIB"mstr_standard";
"B \NAC \NWC"2;
"S \NAC"
BN"2"159;
%"TAP"
"6","(-2850,4125)","2","mstr_standard","I158";
;
HDL_TAP"TRUE"
BODY_TYPE"PLUMBING"
CDS_LIB"mstr_standard";
"B \NAC \NWC"1;
"S \NAC"
BN"6"28;
%"TAP"
"6","(-2850,4075)","2","mstr_standard","I159";
;
HDL_TAP"TRUE"
BODY_TYPE"PLUMBING"
CDS_LIB"mstr_standard";
"B \NAC \NWC"1;
"S \NAC"
BN"5"46;
%"TAP"
"6","(-5575,1225)","0","mstr_standard","I16";
;
HDL_TAP"TRUE"
BODY_TYPE"PLUMBING"
CDS_LIB"mstr_standard";
"B \NAC \NWC"2;
"S \NAC"
BN"3"158;
%"TAP"
"6","(-2850,4175)","2","mstr_standard","I160";
;
HDL_TAP"TRUE"
BODY_TYPE"PLUMBING"
CDS_LIB"mstr_standard";
"B \NAC \NWC"1;
"S \NAC"
BN"7"27;
%"TAP"
"6","(-2850,4275)","2","mstr_standard","I161";
;
HDL_TAP"TRUE"
BODY_TYPE"PLUMBING"
CDS_LIB"mstr_standard";
"B \NAC \NWC"1;
"S \NAC"
BN"9"26;
%"TAP"
"6","(-2850,4225)","2","mstr_standard","I162";
;
HDL_TAP"TRUE"
BODY_TYPE"PLUMBING"
CDS_LIB"mstr_standard";
"B \NAC \NWC"1;
"S \NAC"
BN"8"170;
%"TAP"
"6","(-2850,4425)","2","mstr_standard","I163";
;
HDL_TAP"TRUE"
BODY_TYPE"PLUMBING"
CDS_LIB"mstr_standard";
"B \NAC \NWC"1;
"S \NAC"
BN"12"23;
%"TAP"
"6","(-2850,4375)","2","mstr_standard","I164";
;
HDL_TAP"TRUE"
BODY_TYPE"PLUMBING"
CDS_LIB"mstr_standard";
"B \NAC \NWC"1;
"S \NAC"
BN"11"24;
%"TAP"
"6","(-2850,4325)","2","mstr_standard","I165";
;
HDL_TAP"TRUE"
BODY_TYPE"PLUMBING"
CDS_LIB"mstr_standard";
"B \NAC \NWC"1;
"S \NAC"
BN"10"25;
%"TAP"
"6","(-2850,4475)","2","mstr_standard","I166";
;
HDL_TAP"TRUE"
BODY_TYPE"PLUMBING"
CDS_LIB"mstr_standard";
"B \NAC \NWC"1;
"S \NAC"
BN"13"22;
%"TAP"
"6","(-2850,4525)","2","mstr_standard","I167";
;
HDL_TAP"TRUE"
BODY_TYPE"PLUMBING"
CDS_LIB"mstr_standard";
"B \NAC \NWC"1;
"S \NAC"
BN"14"21;
%"TAP"
"6","(-2850,4575)","2","mstr_standard","I168";
;
HDL_TAP"TRUE"
BODY_TYPE"PLUMBING"
CDS_LIB"mstr_standard";
"B \NAC \NWC"1;
"S \NAC"
BN"15"20;
%"TAP"
"6","(-2850,4625)","2","mstr_standard","I169";
;
HDL_TAP"TRUE"
BODY_TYPE"PLUMBING"
CDS_LIB"mstr_standard";
"B \NAC \NWC"1;
"S \NAC"
BN"16"19;
%"TAP"
"6","(-5575,1275)","0","mstr_standard","I17";
;
HDL_TAP"TRUE"
BODY_TYPE"PLUMBING"
CDS_LIB"mstr_standard";
"B \NAC \NWC"2;
"S \NAC"
BN"4"157;
%"TAP"
"6","(-2850,4675)","2","mstr_standard","I170";
;
HDL_TAP"TRUE"
BODY_TYPE"PLUMBING"
CDS_LIB"mstr_standard";
"B \NAC \NWC"1;
"S \NAC"
BN"17"18;
%"SKX_EXT_B"
"8","(-4175,2575)","0","chpset_lib","I172";
;
CDS_SEC"8"
MATERIAL"IC"
PART_NUMBER"TBD"
LOCATION"U5D1"
ROOM"CPU0"
CDS_LOCATION"U5D1"
SEC"8"
SEC_TYPE"BGA1"
CDS_LIB"chpset_lib"
PACK_TYPE"BGA1";
"DDR5_PAR"
$PN"DK53"67;
"DDR5_ODT<0>"
$PN"DG50"90;
"DDR5_ODT<1>"
$PN"DG48"89;
"DDR5_ODT<2>"
$PN"DK49"165;
"DDR5_ODT<3>"
$PN"DF47"88;
"DDR5_MA<0>"
$PN"DF53"87;
"DDR5_MA<1>"
$PN"DC58"86;
"DDR5_MA<2>"
$PN"DD57"85;
"DDR5_MA<3>"
$PN"DG58"65;
"DDR5_MA<4>"
$PN"DJ58"64;
"DDR5_MA<5>"
$PN"DF59"63;
"DDR5_MA<6>"
$PN"DK59"62;
"DDR5_MA<7>"
$PN"DC60"61;
"DDR5_MA<8>"
$PN"DD59"60;
"DDR5_MA<9>"
$PN"DA58"59;
"DDR5_MA<10>"
$PN"DD55"58;
"DDR5_MA<11>"
$PN"DA60"57;
"DDR5_MA<12>"
$PN"DG60"56;
"DDR5_MA<13>"
$PN"DD53"55;
"DDR5_MA<14>"
$PN"DJ50"54;
"DDR5_MA<15>"
$PN"DC54"53;
"DDR5_MA<16>"
$PN"DG52"52;
"DDR5_MA<17>"
$PN"DE46"51;
"DDR5_ECC<0>"
$PN"CH71"160;
"DDR5_ECC<1>"
$PN"CM71"169;
"DDR5_ECC<2>"
$PN"CJ68"159;
"DDR5_ECC<3>"
$PN"CL68"158;
"DDR5_ECC<4>"
$PN"CJ72"157;
"DDR5_ECC<5>"
$PN"CL72"156;
"DDR5_ECC<6>"
$PN"CH69"155;
"DDR5_ECC<7>"
$PN"CM69"154;
"DDR5_DQS_DP<0>"
$PN"CR76"50;
"DDR5_DQS_DP<1>"
$PN"DE76"49;
"DDR5_DQS_DP<2>"
$PN"DK71"167;
"DDR5_DQS_DP<3>"
$PN"CT65"48;
"DDR5_DQS_DP<4>"
$PN"DJ40"47;
"DDR5_DQS_DP<5>"
$PN"DJ32"46;
"DDR5_DQS_DP<6>"
$PN"DB35"28;
"DDR5_DQS_DP<7>"
$PN"DB29"27;
"DDR5_DQS_DP<8>"
$PN"CL70"170;
"DDR5_DQS_DP<9>"
$PN"CU74"26;
"DDR5_DQS_DP<10>"
$PN"DG74"25;
"DDR5_DQS_DP<11>"
$PN"DH69"24;
"DDR5_DQS_DP<12>"
$PN"CM65"23;
"DDR5_DQS_DP<13>"
$PN"DC40"22;
"DDR5_DQS_DP<14>"
$PN"DE32"21;
"DDR5_DQS_DP<15>"
$PN"CV35"20;
"DDR5_DQS_DP<16>"
$PN"CV29"19;
"DDR5_DQS_DP<17>"
$PN"CG70"18;
"DDR5_DQS_DN<0>"
$PN"CP77"45;
"DDR5_DQS_DN<1>"
$PN"DD77"44;
"DDR5_DQS_DN<2>"
$PN"DL72"43;
"DDR5_DQS_DN<3>"
$PN"CV65"42;
"DDR5_DQS_DN<4>"
$PN"DG40"41;
"DDR5_DQS_DN<5>"
$PN"DL32"40;
"DDR5_DQS_DN<6>"
$PN"DD35"39;
"DDR5_DQS_DN<7>"
$PN"DD29"38;
"DDR5_DQS_DN<8>"
$PN"CN70"37;
"DDR5_DQS_DN<9>"
$PN"CT75"36;
"DDR5_DQS_DN<10>"
$PN"DF75"35;
"DDR5_DQS_DN<11>"
$PN"DJ70"34;
"DDR5_DQS_DN<12>"
$PN"CP65"33;
"DDR5_DQS_DN<13>"
$PN"DE40"32;
"DDR5_DQS_DN<14>"
$PN"DG32"13;
"DDR5_DQS_DN<15>"
$PN"CY35"31;
"DDR5_DQS_DN<16>"
$PN"CY29"30;
"DDR5_DQS_DN<17>"
$PN"CJ70"29;
"DDR5_DQ<0>"
$PN"CR74"153;
"DDR5_DQ<1>"
$PN"CN76"152;
"DDR5_DQ<2>"
$PN"CW76"151;
"DDR5_DQ<3>"
$PN"CV77"150;
"DDR5_DQ<4>"
$PN"CN74"149;
"DDR5_DQ<5>"
$PN"CM75"162;
"DDR5_DQ<6>"
$PN"CV75"148;
"DDR5_DQ<7>"
$PN"CT77"147;
"DDR5_DQ<8>"
$PN"DE74"146;
"DDR5_DQ<9>"
$PN"DC76"145;
"DDR5_DQ<10>"
$PN"DH75"144;
"DDR5_DQ<11>"
$PN"DJ76"135;
"DDR5_DQ<12>"
$PN"DC74"134;
"DDR5_DQ<13>"
$PN"DB75"133;
"DDR5_DQ<14>"
$PN"DF77"132;
"DDR5_DQ<15>"
$PN"DH77"131;
"DDR5_DQ<16>"
$PN"DG70"130;
"DDR5_DQ<17>"
$PN"DJ72"129;
"DDR5_DQ<18>"
$PN"DM69"128;
"DDR5_DQ<19>"
$PN"DN70"127;
"DDR5_DQ<20>"
$PN"DF71"126;
"DDR5_DQ<21>"
$PN"DG72"125;
"DDR5_DQ<22>"
$PN"DK69"124;
"DDR5_DQ<23>"
$PN"DM71"123;
"DDR5_DQ<24>"
$PN"CN66"122;
"DDR5_DQ<25>"
$PN"CU66"121;
"DDR5_DQ<26>"
$PN"CP63"120;
"DDR5_DQ<27>"
$PN"CT63"119;
"DDR5_DQ<28>"
$PN"CP67"118;
"DDR5_DQ<29>"
$PN"CT67"117;
"DDR5_DQ<30>"
$PN"CN64"116;
"DDR5_DQ<31>"
$PN"CU64"115;
"DDR5_DQ<32>"
$PN"DD41"163;
"DDR5_DQ<33>"
$PN"DG42"114;
"DDR5_DQ<34>"
$PN"DE38"164;
"DDR5_DQ<35>"
$PN"DG38"113;
"DDR5_DQ<36>"
$PN"DA42"112;
"DDR5_DQ<37>"
$PN"DE42"111;
"DDR5_DQ<38>"
$PN"DD39"110;
"DDR5_DQ<39>"
$PN"DH39"109;
"DDR5_DQ<40>"
$PN"DF33"108;
"DDR5_DQ<41>"
$PN"DK33"168;
"DDR5_DQ<42>"
$PN"DG30"107;
"DDR5_DQ<43>"
$PN"DJ30"106;
"DDR5_DQ<44>"
$PN"DG34"105;
"DDR5_DQ<45>"
$PN"DJ34"104;
"DDR5_DQ<46>"
$PN"DF31"103;
"DDR5_DQ<47>"
$PN"DK31"102;
"DDR5_DQ<48>"
$PN"CW36"101;
"DDR5_DQ<49>"
$PN"DC36"100;
"DDR5_DQ<50>"
$PN"CY33"14;
"DDR5_DQ<51>"
$PN"DB33"99;
"DDR5_DQ<52>"
$PN"CY37"166;
"DDR5_DQ<53>"
$PN"DB37"98;
"DDR5_DQ<54>"
$PN"CW34"97;
"DDR5_DQ<55>"
$PN"DC34"15;
"DDR5_DQ<56>"
$PN"CW30"16;
"DDR5_DQ<57>"
$PN"DC30"17;
"DDR5_DQ<58>"
$PN"CY27"96;
"DDR5_DQ<59>"
$PN"DB27"95;
"DDR5_DQ<60>"
$PN"CY31"94;
"DDR5_DQ<61>"
$PN"DB31"93;
"DDR5_DQ<62>"
$PN"CW28"92;
"DDR5_DQ<63>"
$PN"DC28"91;
"DDR5_CS_N<0>"
$PN"DK51"84;
"DDR5_CS_N<1>"
$PN"DF49"83;
"DDR5_CS_N<2>"
$PN"DJ46"82;
"DDR5_CS_N<3>"
$PN"DG46"81;
"DDR5_CS_N<4>"
$PN"DF51"80;
"DDR5_CS_N<5>"
$PN"DJ48"79;
"DDR5_CS_N<6>"
$PN"DM45"78;
"DDR5_CS_N<7>"
$PN"DK45"77;
"DDR5_CLK_DP<0>"
$PN"DJ54"143;
"DDR5_CLK_DP<1>"
$PN"DG54"142;
"DDR5_CLK_DP<2>"
$PN"DJ56"141;
"DDR5_CLK_DP<3>"
$PN"DG56"140;
"DDR5_CLK_DN<0>"
$PN"DK55"139;
"DDR5_CLK_DN<1>"
$PN"DF55"138;
"DDR5_CLK_DN<2>"
$PN"DK57"137;
"DDR5_CLK_DN<3>"
$PN"DF57"136;
"DDR5_CKE<0>"
$PN"DG62"76;
"DDR5_CKE<1>"
$PN"DD63"75;
"DDR5_CKE<2>"
$PN"DK63"74;
"DDR5_CKE<3>"
$PN"DF63"73;
"DDR5_CID<2>"
$PN"DF45"161;
"DDR5_BG<0>"
$PN"DA62"72;
"DDR5_BG<1>"
$PN"DF61"71;
"DDR5_BA<0>"
$PN"DJ52"70;
"DDR5_BA<1>"
$PN"DC56"69;
"DDR5_ALERT_N"
$PN"DD61"68;
"DDR5_ACT_N"
$PN"DC62"66;
%"TAP"
"6","(-5575,1325)","0","mstr_standard","I18";
;
HDL_TAP"TRUE"
BODY_TYPE"PLUMBING"
CDS_LIB"mstr_standard";
"B \NAC \NWC"2;
"S \NAC"
BN"5"156;
%"TAP"
"6","(-5575,1375)","0","mstr_standard","I19";
;
HDL_TAP"TRUE"
BODY_TYPE"PLUMBING"
CDS_LIB"mstr_standard";
"B \NAC \NWC"2;
"S \NAC"
BN"6"155;
%"TAP"
"6","(-5575,1425)","0","mstr_standard","I20";
;
HDL_TAP"TRUE"
BODY_TYPE"PLUMBING"
CDS_LIB"mstr_standard";
"B \NAC \NWC"2;
"S \NAC"
BN"7"154;
%"TAP"
"6","(-5575,1575)","0","mstr_standard","I21";
;
HDL_TAP"TRUE"
BODY_TYPE"PLUMBING"
CDS_LIB"mstr_standard";
"B \NAC \NWC"3;
"S \NAC"
BN"1"152;
%"TAP"
"6","(-5575,1525)","0","mstr_standard","I22";
;
HDL_TAP"TRUE"
BODY_TYPE"PLUMBING"
CDS_LIB"mstr_standard";
"B \NAC \NWC"3;
"S \NAC"
BN"0"153;
%"TAP"
"6","(-5575,1625)","0","mstr_standard","I23";
;
HDL_TAP"TRUE"
BODY_TYPE"PLUMBING"
CDS_LIB"mstr_standard";
"B \NAC \NWC"3;
"S \NAC"
BN"2"151;
%"TAP"
"6","(-5575,1675)","0","mstr_standard","I24";
;
HDL_TAP"TRUE"
BODY_TYPE"PLUMBING"
CDS_LIB"mstr_standard";
"B \NAC \NWC"3;
"S \NAC"
BN"3"150;
%"TAP"
"6","(-5575,1725)","0","mstr_standard","I25";
;
HDL_TAP"TRUE"
BODY_TYPE"PLUMBING"
CDS_LIB"mstr_standard";
"B \NAC \NWC"3;
"S \NAC"
BN"4"149;
%"TAP"
"6","(-5575,1775)","0","mstr_standard","I26";
;
HDL_TAP"TRUE"
BODY_TYPE"PLUMBING"
CDS_LIB"mstr_standard";
"B \NAC \NWC"3;
"S \NAC"
BN"5"162;
%"TAP"
"6","(-5575,1825)","0","mstr_standard","I27";
;
HDL_TAP"TRUE"
BODY_TYPE"PLUMBING"
CDS_LIB"mstr_standard";
"B \NAC \NWC"3;
"S \NAC"
BN"6"148;
%"TAP"
"6","(-5575,1925)","0","mstr_standard","I28";
;
HDL_TAP"TRUE"
BODY_TYPE"PLUMBING"
CDS_LIB"mstr_standard";
"B \NAC \NWC"3;
"S \NAC"
BN"8"146;
%"TAP"
"6","(-5575,1875)","0","mstr_standard","I29";
;
HDL_TAP"TRUE"
BODY_TYPE"PLUMBING"
CDS_LIB"mstr_standard";
"B \NAC \NWC"3;
"S \NAC"
BN"7"147;
%"TAP"
"6","(-5575,1975)","0","mstr_standard","I30";
;
HDL_TAP"TRUE"
BODY_TYPE"PLUMBING"
CDS_LIB"mstr_standard";
"B \NAC \NWC"3;
"S \NAC"
BN"9"145;
%"TAP"
"6","(-5575,2025)","0","mstr_standard","I32";
;
HDL_TAP"TRUE"
BODY_TYPE"PLUMBING"
CDS_LIB"mstr_standard";
"B \NAC \NWC"3;
"S \NAC"
BN"10"144;
%"TAP"
"6","(-5575,2075)","0","mstr_standard","I33";
;
HDL_TAP"TRUE"
BODY_TYPE"PLUMBING"
CDS_LIB"mstr_standard";
"B \NAC \NWC"3;
"S \NAC"
BN"11"135;
%"TAP"
"6","(-5575,2125)","0","mstr_standard","I34";
;
HDL_TAP"TRUE"
BODY_TYPE"PLUMBING"
CDS_LIB"mstr_standard";
"B \NAC \NWC"3;
"S \NAC"
BN"12"134;
%"TAP"
"6","(-5575,2175)","0","mstr_standard","I35";
;
HDL_TAP"TRUE"
BODY_TYPE"PLUMBING"
CDS_LIB"mstr_standard";
"B \NAC \NWC"3;
"S \NAC"
BN"13"133;
%"TAP"
"6","(-5575,2225)","0","mstr_standard","I36";
;
HDL_TAP"TRUE"
BODY_TYPE"PLUMBING"
CDS_LIB"mstr_standard";
"B \NAC \NWC"3;
"S \NAC"
BN"14"132;
%"TAP"
"6","(-5575,2275)","0","mstr_standard","I37";
;
HDL_TAP"TRUE"
BODY_TYPE"PLUMBING"
CDS_LIB"mstr_standard";
"B \NAC \NWC"3;
"S \NAC"
BN"15"131;
%"TAP"
"6","(-5575,2325)","0","mstr_standard","I38";
;
HDL_TAP"TRUE"
BODY_TYPE"PLUMBING"
CDS_LIB"mstr_standard";
"B \NAC \NWC"3;
"S \NAC"
BN"16"130;
%"TAP"
"6","(-5575,2375)","0","mstr_standard","I39";
;
HDL_TAP"TRUE"
BODY_TYPE"PLUMBING"
CDS_LIB"mstr_standard";
"B \NAC \NWC"3;
"S \NAC"
BN"17"129;
%"TAP"
"6","(-5575,2425)","0","mstr_standard","I40";
;
HDL_TAP"TRUE"
BODY_TYPE"PLUMBING"
CDS_LIB"mstr_standard";
"B \NAC \NWC"3;
"S \NAC"
BN"18"128;
%"TAP"
"6","(-5575,2475)","0","mstr_standard","I41";
;
HDL_TAP"TRUE"
BODY_TYPE"PLUMBING"
CDS_LIB"mstr_standard";
"B \NAC \NWC"3;
"S \NAC"
BN"19"127;
%"TAP"
"6","(-5575,2525)","0","mstr_standard","I42";
;
HDL_TAP"TRUE"
BODY_TYPE"PLUMBING"
CDS_LIB"mstr_standard";
"B \NAC \NWC"3;
"S \NAC"
BN"20"126;
%"TAP"
"6","(-5575,2575)","0","mstr_standard","I43";
;
HDL_TAP"TRUE"
BODY_TYPE"PLUMBING"
CDS_LIB"mstr_standard";
"B \NAC \NWC"3;
"S \NAC"
BN"21"125;
%"TAP"
"6","(-5575,2625)","0","mstr_standard","I44";
;
HDL_TAP"TRUE"
BODY_TYPE"PLUMBING"
CDS_LIB"mstr_standard";
"B \NAC \NWC"3;
"S \NAC"
BN"22"124;
%"TAP"
"6","(-5575,2675)","0","mstr_standard","I45";
;
HDL_TAP"TRUE"
BODY_TYPE"PLUMBING"
CDS_LIB"mstr_standard";
"B \NAC \NWC"3;
"S \NAC"
BN"23"123;
%"TAP"
"6","(-5575,2725)","0","mstr_standard","I46";
;
HDL_TAP"TRUE"
BODY_TYPE"PLUMBING"
CDS_LIB"mstr_standard";
"B \NAC \NWC"3;
"S \NAC"
BN"24"122;
%"TAP"
"6","(-5575,2825)","0","mstr_standard","I47";
;
HDL_TAP"TRUE"
BODY_TYPE"PLUMBING"
CDS_LIB"mstr_standard";
"B \NAC \NWC"3;
"S \NAC"
BN"26"120;
%"TAP"
"6","(-5575,2775)","0","mstr_standard","I48";
;
HDL_TAP"TRUE"
BODY_TYPE"PLUMBING"
CDS_LIB"mstr_standard";
"B \NAC \NWC"3;
"S \NAC"
BN"25"121;
%"TAP"
"6","(-5575,2875)","0","mstr_standard","I49";
;
HDL_TAP"TRUE"
BODY_TYPE"PLUMBING"
CDS_LIB"mstr_standard";
"B \NAC \NWC"3;
"S \NAC"
BN"27"119;
%"TAP"
"6","(-5575,625)","0","mstr_standard","I5";
;
HDL_TAP"TRUE"
BODY_TYPE"PLUMBING"
CDS_LIB"mstr_standard";
"B \NAC \NWC"6;
"S \NAC"
BN"0"139;
%"TAP"
"6","(-5575,2925)","0","mstr_standard","I50";
;
HDL_TAP"TRUE"
BODY_TYPE"PLUMBING"
CDS_LIB"mstr_standard";
"B \NAC \NWC"3;
"S \NAC"
BN"28"118;
%"TAP"
"6","(-5575,2975)","0","mstr_standard","I51";
;
HDL_TAP"TRUE"
BODY_TYPE"PLUMBING"
CDS_LIB"mstr_standard";
"B \NAC \NWC"3;
"S \NAC"
BN"29"117;
%"TAP"
"6","(-5575,3075)","0","mstr_standard","I52";
;
HDL_TAP"TRUE"
BODY_TYPE"PLUMBING"
CDS_LIB"mstr_standard";
"B \NAC \NWC"3;
"S \NAC"
BN"31"115;
%"TAP"
"6","(-5575,3025)","0","mstr_standard","I53";
;
HDL_TAP"TRUE"
BODY_TYPE"PLUMBING"
CDS_LIB"mstr_standard";
"B \NAC \NWC"3;
"S \NAC"
BN"30"116;
%"TAP"
"6","(-5575,3125)","0","mstr_standard","I54";
;
HDL_TAP"TRUE"
BODY_TYPE"PLUMBING"
CDS_LIB"mstr_standard";
"B \NAC \NWC"3;
"S \NAC"
BN"32"163;
%"TAP"
"6","(-5575,3175)","0","mstr_standard","I55";
;
HDL_TAP"TRUE"
BODY_TYPE"PLUMBING"
CDS_LIB"mstr_standard";
"B \NAC \NWC"3;
"S \NAC"
BN"33"114;
%"TAP"
"6","(-5575,3225)","0","mstr_standard","I56";
;
HDL_TAP"TRUE"
BODY_TYPE"PLUMBING"
CDS_LIB"mstr_standard";
"B \NAC \NWC"3;
"S \NAC"
BN"34"164;
%"TAP"
"6","(-5575,3275)","0","mstr_standard","I57";
;
HDL_TAP"TRUE"
BODY_TYPE"PLUMBING"
CDS_LIB"mstr_standard";
"B \NAC \NWC"3;
"S \NAC"
BN"35"113;
%"TAP"
"6","(-5575,3325)","0","mstr_standard","I58";
;
HDL_TAP"TRUE"
BODY_TYPE"PLUMBING"
CDS_LIB"mstr_standard";
"B \NAC \NWC"3;
"S \NAC"
BN"36"112;
%"TAP"
"6","(-5575,3375)","0","mstr_standard","I59";
;
HDL_TAP"TRUE"
BODY_TYPE"PLUMBING"
CDS_LIB"mstr_standard";
"B \NAC \NWC"3;
"S \NAC"
BN"37"111;
%"TAP"
"6","(-5575,675)","0","mstr_standard","I6";
;
HDL_TAP"TRUE"
BODY_TYPE"PLUMBING"
CDS_LIB"mstr_standard";
"B \NAC \NWC"6;
"S \NAC"
BN"1"138;
%"TAP"
"6","(-5575,3425)","0","mstr_standard","I60";
;
HDL_TAP"TRUE"
BODY_TYPE"PLUMBING"
CDS_LIB"mstr_standard";
"B \NAC \NWC"3;
"S \NAC"
BN"38"110;
%"TAP"
"6","(-5575,3475)","0","mstr_standard","I61";
;
HDL_TAP"TRUE"
BODY_TYPE"PLUMBING"
CDS_LIB"mstr_standard";
"B \NAC \NWC"3;
"S \NAC"
BN"39"109;
%"TAP"
"6","(-5575,3525)","0","mstr_standard","I62";
;
HDL_TAP"TRUE"
BODY_TYPE"PLUMBING"
CDS_LIB"mstr_standard";
"B \NAC \NWC"3;
"S \NAC"
BN"40"108;
%"TAP"
"6","(-5575,3575)","0","mstr_standard","I63";
;
HDL_TAP"TRUE"
BODY_TYPE"PLUMBING"
CDS_LIB"mstr_standard";
"B \NAC \NWC"3;
"S \NAC"
BN"41"168;
%"TAP"
"6","(-5575,3625)","0","mstr_standard","I64";
;
HDL_TAP"TRUE"
BODY_TYPE"PLUMBING"
CDS_LIB"mstr_standard";
"B \NAC \NWC"3;
"S \NAC"
BN"42"107;
%"TAP"
"6","(-5575,3675)","0","mstr_standard","I65";
;
HDL_TAP"TRUE"
BODY_TYPE"PLUMBING"
CDS_LIB"mstr_standard";
"B \NAC \NWC"3;
"S \NAC"
BN"43"106;
%"TAP"
"6","(-5575,3725)","0","mstr_standard","I66";
;
HDL_TAP"TRUE"
BODY_TYPE"PLUMBING"
CDS_LIB"mstr_standard";
"B \NAC \NWC"3;
"S \NAC"
BN"44"105;
%"TAP"
"6","(-5575,3775)","0","mstr_standard","I67";
;
HDL_TAP"TRUE"
BODY_TYPE"PLUMBING"
CDS_LIB"mstr_standard";
"B \NAC \NWC"3;
"S \NAC"
BN"45"104;
%"TAP"
"6","(-5575,3825)","0","mstr_standard","I68";
;
HDL_TAP"TRUE"
BODY_TYPE"PLUMBING"
CDS_LIB"mstr_standard";
"B \NAC \NWC"3;
"S \NAC"
BN"46"103;
%"TAP"
"6","(-5575,3875)","0","mstr_standard","I69";
;
HDL_TAP"TRUE"
BODY_TYPE"PLUMBING"
CDS_LIB"mstr_standard";
"B \NAC \NWC"3;
"S \NAC"
BN"47"102;
%"TAP"
"6","(-5575,775)","0","mstr_standard","I7";
;
HDL_TAP"TRUE"
BODY_TYPE"PLUMBING"
CDS_LIB"mstr_standard";
"B \NAC \NWC"6;
"S \NAC"
BN"3"136;
%"TAP"
"6","(-5575,3925)","0","mstr_standard","I70";
;
HDL_TAP"TRUE"
BODY_TYPE"PLUMBING"
CDS_LIB"mstr_standard";
"B \NAC \NWC"3;
"S \NAC"
BN"48"101;
%"TAP"
"6","(-5575,3975)","0","mstr_standard","I71";
;
HDL_TAP"TRUE"
BODY_TYPE"PLUMBING"
CDS_LIB"mstr_standard";
"B \NAC \NWC"3;
"S \NAC"
BN"49"100;
%"TAP"
"6","(-5575,4025)","0","mstr_standard","I72";
;
HDL_TAP"TRUE"
BODY_TYPE"PLUMBING"
CDS_LIB"mstr_standard";
"B \NAC \NWC"3;
"S \NAC"
BN"50"14;
%"TAP"
"6","(-5575,4075)","0","mstr_standard","I74";
;
HDL_TAP"TRUE"
BODY_TYPE"PLUMBING"
CDS_LIB"mstr_standard";
"B \NAC \NWC"3;
"S \NAC"
BN"51"99;
%"TAP"
"6","(-5575,4125)","0","mstr_standard","I75";
;
HDL_TAP"TRUE"
BODY_TYPE"PLUMBING"
CDS_LIB"mstr_standard";
"B \NAC \NWC"3;
"S \NAC"
BN"52"166;
%"TAP"
"6","(-5575,4175)","0","mstr_standard","I76";
;
HDL_TAP"TRUE"
BODY_TYPE"PLUMBING"
CDS_LIB"mstr_standard";
"B \NAC \NWC"3;
"S \NAC"
BN"53"98;
%"TAP"
"6","(-5575,4225)","0","mstr_standard","I77";
;
HDL_TAP"TRUE"
BODY_TYPE"PLUMBING"
CDS_LIB"mstr_standard";
"B \NAC \NWC"3;
"S \NAC"
BN"54"97;
%"TAP"
"6","(-5575,4275)","0","mstr_standard","I78";
;
HDL_TAP"TRUE"
BODY_TYPE"PLUMBING"
CDS_LIB"mstr_standard";
"B \NAC \NWC"3;
"S \NAC"
BN"55"15;
%"TAP"
"6","(-5575,4325)","0","mstr_standard","I79";
;
HDL_TAP"TRUE"
BODY_TYPE"PLUMBING"
CDS_LIB"mstr_standard";
"B \NAC \NWC"3;
"S \NAC"
BN"56"16;
%"TAP"
"6","(-5575,725)","0","mstr_standard","I8";
;
HDL_TAP"TRUE"
BODY_TYPE"PLUMBING"
CDS_LIB"mstr_standard";
"B \NAC \NWC"6;
"S \NAC"
BN"2"137;
%"TAP"
"6","(-5575,4375)","0","mstr_standard","I80";
;
HDL_TAP"TRUE"
BODY_TYPE"PLUMBING"
CDS_LIB"mstr_standard";
"B \NAC \NWC"3;
"S \NAC"
BN"57"17;
%"TAP"
"6","(-5575,4425)","0","mstr_standard","I81";
;
HDL_TAP"TRUE"
BODY_TYPE"PLUMBING"
CDS_LIB"mstr_standard";
"B \NAC \NWC"3;
"S \NAC"
BN"58"96;
%"TAP"
"6","(-5575,4475)","0","mstr_standard","I82";
;
HDL_TAP"TRUE"
BODY_TYPE"PLUMBING"
CDS_LIB"mstr_standard";
"B \NAC \NWC"3;
"S \NAC"
BN"59"95;
%"TAP"
"6","(-5575,4525)","0","mstr_standard","I83";
;
HDL_TAP"TRUE"
BODY_TYPE"PLUMBING"
CDS_LIB"mstr_standard";
"B \NAC \NWC"3;
"S \NAC"
BN"60"94;
%"TAP"
"6","(-5575,4575)","0","mstr_standard","I84";
;
HDL_TAP"TRUE"
BODY_TYPE"PLUMBING"
CDS_LIB"mstr_standard";
"B \NAC \NWC"3;
"S \NAC"
BN"61"93;
%"TAP"
"6","(-5575,4625)","0","mstr_standard","I85";
;
HDL_TAP"TRUE"
BODY_TYPE"PLUMBING"
CDS_LIB"mstr_standard";
"B \NAC \NWC"3;
"S \NAC"
BN"62"92;
%"TAP"
"6","(-5575,4675)","0","mstr_standard","I86";
;
HDL_TAP"TRUE"
BODY_TYPE"PLUMBING"
CDS_LIB"mstr_standard";
"B \NAC \NWC"3;
"S \NAC"
BN"63"91;
%"TAP"
"6","(-2850,825)","2","mstr_standard","I87";
;
HDL_TAP"TRUE"
BODY_TYPE"PLUMBING"
CDS_LIB"mstr_standard";
"B \NAC \NWC"10;
"S \NAC"
BN"0"72;
%"TAP"
"6","(-2850,775)","2","mstr_standard","I88";
;
HDL_TAP"TRUE"
BODY_TYPE"PLUMBING"
CDS_LIB"mstr_standard";
"B \NAC \NWC"11;
"S \NAC"
BN"1"69;
%"TAP"
"6","(-2850,725)","2","mstr_standard","I89";
;
HDL_TAP"TRUE"
BODY_TYPE"PLUMBING"
CDS_LIB"mstr_standard";
"B \NAC \NWC"11;
"S \NAC"
BN"0"70;
%"TAP"
"6","(-5575,825)","0","mstr_standard","I9";
;
HDL_TAP"TRUE"
BODY_TYPE"PLUMBING"
CDS_LIB"mstr_standard";
"B \NAC \NWC"5;
"S \NAC"
BN"0"143;
%"TAP"
"6","(-2850,875)","2","mstr_standard","I90";
;
HDL_TAP"TRUE"
BODY_TYPE"PLUMBING"
CDS_LIB"mstr_standard";
"B \NAC \NWC"10;
"S \NAC"
BN"1"71;
%"TAP"
"6","(-2850,1025)","2","mstr_standard","I91";
;
HDL_TAP"TRUE"
BODY_TYPE"PLUMBING"
CDS_LIB"mstr_standard";
"B \NAC \NWC"8;
"S \NAC"
BN"1"83;
%"TAP"
"6","(-2850,975)","2","mstr_standard","I92";
;
HDL_TAP"TRUE"
BODY_TYPE"PLUMBING"
CDS_LIB"mstr_standard";
"B \NAC \NWC"8;
"S \NAC"
BN"0"84;
%"TAP"
"6","(-2850,1075)","2","mstr_standard","I93";
;
HDL_TAP"TRUE"
BODY_TYPE"PLUMBING"
CDS_LIB"mstr_standard";
"B \NAC \NWC"8;
"S \NAC"
BN"2"82;
%"TAP"
"6","(-2850,1225)","2","mstr_standard","I94";
;
HDL_TAP"TRUE"
BODY_TYPE"PLUMBING"
CDS_LIB"mstr_standard";
"B \NAC \NWC"8;
"S \NAC"
BN"5"79;
%"TAP"
"6","(-2850,1125)","2","mstr_standard","I95";
;
HDL_TAP"TRUE"
BODY_TYPE"PLUMBING"
CDS_LIB"mstr_standard";
"B \NAC \NWC"8;
"S \NAC"
BN"3"81;
%"TAP"
"6","(-2850,1175)","2","mstr_standard","I96";
;
HDL_TAP"TRUE"
BODY_TYPE"PLUMBING"
CDS_LIB"mstr_standard";
"B \NAC \NWC"8;
"S \NAC"
BN"4"80;
%"TAP"
"6","(-2850,1275)","2","mstr_standard","I97";
;
HDL_TAP"TRUE"
BODY_TYPE"PLUMBING"
CDS_LIB"mstr_standard";
"B \NAC \NWC"8;
"S \NAC"
BN"6"78;
%"TAP"
"6","(-2850,1325)","2","mstr_standard","I98";
;
HDL_TAP"TRUE"
BODY_TYPE"PLUMBING"
CDS_LIB"mstr_standard";
"B \NAC \NWC"8;
"S \NAC"
BN"7"77;
%"TAP"
"6","(-2850,1475)","2","mstr_standard","I99";
;
HDL_TAP"TRUE"
BODY_TYPE"PLUMBING"
CDS_LIB"mstr_standard";
"B \NAC \NWC"4;
"S \NAC"
BN"1"89;
END.
